#ISCELL
  pure_quanta quanta_title_block_c *
  *
#ISCELL
  standard offpage *
  page26_i104
#ISCELL
  standard offpage *
  page26_i105
#CELL
  pure_quanta genoa_sp5 *
  page26_i59
#ISCELL
  standard offpage *
  page26_i86
#ISCELL
  standard offpage *
  page26_i87
